# S9S_MB_2U (Grand Teton) — schematic netlist excerpt (pin names and nets, part order shuffled) for the footprints in the layout excerpt that follows; sources: Cadence DE-HDL packaged netlist, KiCad conversion of 03242023_DA0F0TMBIJ0_F0T_Motherboard_J_brd_V01_OCP.brd

PR1800  Q_RES  3.3 1% CHIP  pkg 0402LF  page 289 : A = SW_PVCCFA_EHV_FIVRA_CPU1_BOOT1 ; B = SW_PVCCFA_EHV_FIVRA_CPU1_BOOT1_
R2412  Q_RES  0 5% CHIP  pkg 0402LF  page 214 : A = PWRGD_DSW_PWROK ; B = PWRGD_DSW_PWROK_R3

(kicad_pcb
	(version 20260206)
	(generator "pcbnew")
	(generator_version "10.0")
	(general
		(thickness 1.6)
		(legacy_teardrops no)
	)
	(paper "A4")
	(title_block
		(title "03242023_DA0F0TMBIJ0_F0T_Motherboard_J_brd_V01_OCP.brd")
		(comment 1 "Grand Teton / footprints 3206-3207 of 6105")
	)
	(layers
		(0 "F.Cu" signal "TOP")
		(4 "In1.Cu" signal "GND")
		(6 "In2.Cu" signal "IN1")
		(8 "In3.Cu" signal "GND1")
		(10 "In4.Cu" signal "IN2")
		(12 "In5.Cu" signal "GND2")
		(14 "In6.Cu" signal "IN3")
		(16 "In7.Cu" signal "GND3")
		(18 "In8.Cu" signal "VCC")
		(20 "In9.Cu" signal "VCC1")
		(22 "In10.Cu" signal "GND4")
		(24 "In11.Cu" signal "IN4")
		(26 "In12.Cu" signal "GND5")
		(28 "In13.Cu" signal "IN5")
		(30 "In14.Cu" signal "GND6")
		(32 "In15.Cu" signal "IN6")
		(34 "In16.Cu" signal "GND7")
		(2 "B.Cu" signal "BOTTOM")
		(9 "F.Adhes" user "F.Adhesive")
		(11 "B.Adhes" user "B.Adhesive")
		(13 "F.Paste" user "Package Geometry/Pastemask Top")
		(15 "B.Paste" user "Package Geometry/Pastemask Bottom")
		(5 "F.SilkS" user "Ref Des/Silkscreen Top")
		(7 "B.SilkS" user "Ref Des/Silkscreen Bottom")
		(1 "F.Mask" user "Board Geometry/Soldermask Top")
		(3 "B.Mask" user "Board Geometry/Soldermask Bottom")
		(17 "Dwgs.User" user "User.Drawings")
		(19 "Cmts.User" user "User.Comments")
		(21 "Eco1.User" user "User.Eco1")
		(23 "Eco2.User" user "User.Eco2")
		(25 "Edge.Cuts" user "Board Geometry/Outline")
		(27 "Margin" user)
		(31 "F.CrtYd" user "Package Geometry/Place Bound Top")
		(29 "B.CrtYd" user "Package Geometry/Place Bound Bottom")
		(35 "F.Fab" user "Ref Des/Assembly Top")
		(33 "B.Fab" user "Ref Des/Assembly Bottom")
	)
	(footprint ""
		(layer "F.Cu")
		(at 172.7835 -358.15778 90)
		(property "Reference" "PR1800"
			(at 0 0 90)
			(layer "F.SilkS")
			(hide yes)
			(effects
				(font
					(size 1.27 1.27)
				)
			)
		)
		(property "Value" ""
			(at 0 0 90)
			(layer "F.Fab")
			(effects
				(font
					(size 1.27 1.27)
				)
			)
		)
		(duplicate_pad_numbers_are_jumpers no)
		(fp_line
			(start 0.7874 -0.4064)
			(end 0.7874 0.4064)
			(stroke
				(width 0.1524)
				(type default)
			)
			(layer "F.SilkS")
		)
		(fp_line
			(start -0.7874 -0.4064)
			(end 0.7874 -0.4064)
			(stroke
				(width 0.1524)
				(type default)
			)
			(layer "F.SilkS")
		)
		(fp_line
			(start 0.7874 0.4064)
			(end -0.7874 0.4064)
			(stroke
				(width 0.1524)
				(type default)
			)
			(layer "F.SilkS")
		)
		(fp_line
			(start -0.7874 0.4064)
			(end -0.7874 -0.4064)
			(stroke
				(width 0.1524)
				(type default)
			)
			(layer "F.SilkS")
		)
		(fp_line
			(start -0.12065 -0.305054)
			(end -0.12065 -0.2794)
			(stroke
				(width 0.1)
				(type default)
			)
			(layer "F.Fab")
		)
		(fp_line
			(start -0.67945 -0.305054)
			(end -0.12065 -0.305054)
			(stroke
				(width 0.1)
				(type default)
			)
			(layer "F.Fab")
		)
		(fp_line
			(start 0.67945 -0.3048)
			(end 0.67945 0.3048)
			(stroke
				(width 0.1)
				(type default)
			)
			(layer "F.Fab")
		)
		(fp_line
			(start 0.12065 -0.3048)
			(end 0.67945 -0.3048)
			(stroke
				(width 0.1)
				(type default)
			)
			(layer "F.Fab")
		)
		(fp_line
			(start 0.12065 -0.2794)
			(end 0.12065 -0.3048)
			(stroke
				(width 0.1)
				(type default)
			)
			(layer "F.Fab")
		)
		(fp_line
			(start -0.12065 -0.2794)
			(end 0.12065 -0.2794)
			(stroke
				(width 0.1)
				(type default)
			)
			(layer "F.Fab")
		)
		(fp_line
			(start 0.120396 0.2794)
			(end -0.12065 0.2794)
			(stroke
				(width 0.1)
				(type default)
			)
			(layer "F.Fab")
		)
		(fp_line
			(start -0.12065 0.2794)
			(end -0.12065 0.3048)
			(stroke
				(width 0.1)
				(type default)
			)
			(layer "F.Fab")
		)
		(fp_line
			(start 0.67945 0.3048)
			(end 0.120396 0.3048)
			(stroke
				(width 0.1)
				(type default)
			)
			(layer "F.Fab")
		)
		(fp_line
			(start 0.120396 0.3048)
			(end 0.120396 0.2794)
			(stroke
				(width 0.1)
				(type default)
			)
			(layer "F.Fab")
		)
		(fp_line
			(start -0.12065 0.3048)
			(end -0.67945 0.3048)
			(stroke
				(width 0.1)
				(type default)
			)
			(layer "F.Fab")
		)
		(fp_line
			(start -0.67945 0.3048)
			(end -0.67945 -0.305054)
			(stroke
				(width 0.1)
				(type default)
			)
			(layer "F.Fab")
		)
		(pad "1" smd circle
			(at -0.40005 0 90)
			(size 0 0)
			(layers "F.Cu" "F.Mask" "F.Paste")
			(net "SW_PVCCFA_EHV_FIVRA_CPU1_BOOT1")
		)
		(pad "2" smd circle
			(at 0.40005 0 90)
			(size 0 0)
			(layers "F.Cu" "F.Mask" "F.Paste")
			(net "SW_PVCCFA_EHV_FIVRA_CPU1_BOOT1_")
		)
	)
	(footprint ""
		(layer "F.Cu")
		(at 320.81216 -26.700988 -90)
		(property "Reference" "R2412"
			(at 0 0 270)
			(layer "F.SilkS")
			(hide yes)
			(effects
				(font
					(size 1.27 1.27)
				)
			)
		)
		(property "Value" ""
			(at 0 0 270)
			(layer "F.Fab")
			(effects
				(font
					(size 1.27 1.27)
				)
			)
		)
		(duplicate_pad_numbers_are_jumpers no)
		(fp_line
			(start -0.7874 0.4064)
			(end -0.7874 -0.4064)
			(stroke
				(width 0.1524)
				(type default)
			)
			(layer "F.SilkS")
		)
		(fp_line
			(start 0.7874 0.4064)
			(end -0.7874 0.4064)
			(stroke
				(width 0.1524)
				(type default)
			)
			(layer "F.SilkS")
		)
		(fp_line
			(start -0.7874 -0.4064)
			(end 0.7874 -0.4064)
			(stroke
				(width 0.1524)
				(type default)
			)
			(layer "F.SilkS")
		)
		(fp_line
			(start 0.7874 -0.4064)
			(end 0.7874 0.4064)
			(stroke
				(width 0.1524)
				(type default)
			)
			(layer "F.SilkS")
		)
		(fp_line
			(start -0.67945 0.3048)
			(end -0.67945 -0.305054)
			(stroke
				(width 0.1)
				(type default)
			)
			(layer "F.Fab")
		)
		(fp_line
			(start -0.12065 0.3048)
			(end -0.67945 0.3048)
			(stroke
				(width 0.1)
				(type default)
			)
			(layer "F.Fab")
		)
		(fp_line
			(start 0.120396 0.3048)
			(end 0.120396 0.2794)
			(stroke
				(width 0.1)
				(type default)
			)
			(layer "F.Fab")
		)
		(fp_line
			(start 0.67945 0.3048)
			(end 0.120396 0.3048)
			(stroke
				(width 0.1)
				(type default)
			)
			(layer "F.Fab")
		)
		(fp_line
			(start -0.12065 0.2794)
			(end -0.12065 0.3048)
			(stroke
				(width 0.1)
				(type default)
			)
			(layer "F.Fab")
		)
		(fp_line
			(start 0.120396 0.2794)
			(end -0.12065 0.2794)
			(stroke
				(width 0.1)
				(type default)
			)
			(layer "F.Fab")
		)
		(fp_line
			(start -0.12065 -0.2794)
			(end 0.12065 -0.2794)
			(stroke
				(width 0.1)
				(type default)
			)
			(layer "F.Fab")
		)
		(fp_line
			(start 0.12065 -0.2794)
			(end 0.12065 -0.3048)
			(stroke
				(width 0.1)
				(type default)
			)
			(layer "F.Fab")
		)
		(fp_line
			(start 0.12065 -0.3048)
			(end 0.67945 -0.3048)
			(stroke
				(width 0.1)
				(type default)
			)
			(layer "F.Fab")
		)
		(fp_line
			(start 0.67945 -0.3048)
			(end 0.67945 0.3048)
			(stroke
				(width 0.1)
				(type default)
			)
			(layer "F.Fab")
		)
		(fp_line
			(start -0.67945 -0.305054)
			(end -0.12065 -0.305054)
			(stroke
				(width 0.1)
				(type default)
			)
			(layer "F.Fab")
		)
		(fp_line
			(start -0.12065 -0.305054)
			(end -0.12065 -0.2794)
			(stroke
				(width 0.1)
				(type default)
			)
			(layer "F.Fab")
		)
		(pad "1" smd circle
			(at -0.40005 0 270)
			(size 0 0)
			(layers "F.Cu" "F.Mask" "F.Paste")
			(net "PWRGD_DSW_PWROK")
		)
		(pad "2" smd circle
			(at 0.40005 0 270)
			(size 0 0)
			(layers "F.Cu" "F.Mask" "F.Paste")
			(net "PWRGD_DSW_PWROK_R3")
		)
	)
)
